(kicad_pcb
	(version 20260206)
	(generator "pcbnew")
	(generator_version "10.0")
	(general
		(thickness 1.6)
		(legacy_teardrops no)
	)
	(paper "A4")
	(title_block
		(title "03242023_DA0F0TMBIJ0_F0T_Motherboard_J_brd_V01_OCP.brd")
		(comment 1 "Grand Teton / footprints 4765-4771 of 6105")
	)
	(layers
		(0 "F.Cu" signal "TOP")
		(4 "In1.Cu" signal "GND")
		(6 "In2.Cu" signal "IN1")
		(8 "In3.Cu" signal "GND1")
		(10 "In4.Cu" signal "IN2")
		(12 "In5.Cu" signal "GND2")
		(14 "In6.Cu" signal "IN3")
		(16 "In7.Cu" signal "GND3")
		(18 "In8.Cu" signal "VCC")
		(20 "In9.Cu" signal "VCC1")
		(22 "In10.Cu" signal "GND4")
		(24 "In11.Cu" signal "IN4")
		(26 "In12.Cu" signal "GND5")
		(28 "In13.Cu" signal "IN5")
		(30 "In14.Cu" signal "GND6")
		(32 "In15.Cu" signal "IN6")
		(34 "In16.Cu" signal "GND7")
		(2 "B.Cu" signal "BOTTOM")
		(9 "F.Adhes" user "F.Adhesive")
		(11 "B.Adhes" user "B.Adhesive")
		(13 "F.Paste" user "Package Geometry/Pastemask Top")
		(15 "B.Paste" user "Package Geometry/Pastemask Bottom")
		(5 "F.SilkS" user "Ref Des/Silkscreen Top")
		(7 "B.SilkS" user "Ref Des/Silkscreen Bottom")
		(1 "F.Mask" user "Board Geometry/Soldermask Top")
		(3 "B.Mask" user "Board Geometry/Soldermask Bottom")
		(17 "Dwgs.User" user "User.Drawings")
		(19 "Cmts.User" user "User.Comments")
		(21 "Eco1.User" user "User.Eco1")
		(23 "Eco2.User" user "User.Eco2")
		(25 "Edge.Cuts" user "Board Geometry/Outline")
		(27 "Margin" user)
		(31 "F.CrtYd" user "Package Geometry/Place Bound Top")
		(29 "B.CrtYd" user "Package Geometry/Place Bound Bottom")
		(35 "F.Fab" user "Ref Des/Assembly Top")
		(33 "B.Fab" user "Ref Des/Assembly Bottom")
	)
	(footprint ""
		(layer "B.Cu")
		(at 243.485924 -396.056104 180)
		(property "Reference" "PC1750"
			(at 0 0 0)
			(layer "B.SilkS")
			(hide yes)
			(effects
				(font
					(size 1.27 1.27)
				)
				(justify mirror)
			)
		)
		(property "Value" ""
			(at 0 0 0)
			(layer "B.Fab")
			(effects
				(font
					(size 1.27 1.27)
				)
				(justify mirror)
			)
		)
		(duplicate_pad_numbers_are_jumpers no)
		(fp_line
			(start 0.7874 0.4064)
			(end 0.7874 -0.4064)
			(stroke
				(width 0.1524)
				(type default)
			)
			(layer "B.SilkS")
		)
		(fp_line
			(start 0.7874 -0.4064)
			(end -0.7874 -0.4064)
			(stroke
				(width 0.1524)
				(type default)
			)
			(layer "B.SilkS")
		)
		(fp_line
			(start -0.7874 0.4064)
			(end 0.7874 0.4064)
			(stroke
				(width 0.1524)
				(type default)
			)
			(layer "B.SilkS")
		)
		(fp_line
			(start -0.7874 -0.4064)
			(end -0.7874 0.4064)
			(stroke
				(width 0.1524)
				(type default)
			)
			(layer "B.SilkS")
		)
		(fp_line
			(start 0.67945 0.3048)
			(end 0.67945 -0.305054)
			(stroke
				(width 0.1)
				(type default)
			)
			(layer "B.Fab")
		)
		(fp_line
			(start 0.67945 -0.305054)
			(end 0.12065 -0.305054)
			(stroke
				(width 0.1)
				(type default)
			)
			(layer "B.Fab")
		)
		(fp_line
			(start 0.12065 0.3048)
			(end 0.67945 0.3048)
			(stroke
				(width 0.1)
				(type default)
			)
			(layer "B.Fab")
		)
		(fp_line
			(start 0.12065 0.2794)
			(end 0.12065 0.3048)
			(stroke
				(width 0.1)
				(type default)
			)
			(layer "B.Fab")
		)
		(fp_line
			(start 0.12065 -0.2794)
			(end -0.12065 -0.2794)
			(stroke
				(width 0.1)
				(type default)
			)
			(layer "B.Fab")
		)
		(fp_line
			(start 0.12065 -0.305054)
			(end 0.12065 -0.2794)
			(stroke
				(width 0.1)
				(type default)
			)
			(layer "B.Fab")
		)
		(fp_line
			(start -0.120396 0.3048)
			(end -0.120396 0.2794)
			(stroke
				(width 0.1)
				(type default)
			)
			(layer "B.Fab")
		)
		(fp_line
			(start -0.120396 0.2794)
			(end 0.12065 0.2794)
			(stroke
				(width 0.1)
				(type default)
			)
			(layer "B.Fab")
		)
		(fp_line
			(start -0.12065 -0.2794)
			(end -0.12065 -0.3048)
			(stroke
				(width 0.1)
				(type default)
			)
			(layer "B.Fab")
		)
		(fp_line
			(start -0.12065 -0.3048)
			(end -0.67945 -0.3048)
			(stroke
				(width 0.1)
				(type default)
			)
			(layer "B.Fab")
		)
		(fp_line
			(start -0.67945 0.3048)
			(end -0.120396 0.3048)
			(stroke
				(width 0.1)
				(type default)
			)
			(layer "B.Fab")
		)
		(fp_line
			(start -0.67945 -0.3048)
			(end -0.67945 0.3048)
			(stroke
				(width 0.1)
				(type default)
			)
			(layer "B.Fab")
		)
		(pad "1" smd circle
			(at 0.40005 0)
			(size 0 0)
			(layers "B.Cu" "B.Mask" "B.Paste")
			(net "P12V_AUX")
		)
		(pad "2" smd circle
			(at -0.40005 0)
			(size 0 0)
			(layers "B.Cu" "B.Mask" "B.Paste")
			(net "P12V_HSC_GATE2")
		)
	)
	(footprint ""
		(layer "B.Cu")
		(at 332.447138 -190.82893 90)
		(property "Reference" "R25"
			(at 0 0 90)
			(layer "B.SilkS")
			(hide yes)
			(effects
				(font
					(size 1.27 1.27)
				)
				(justify mirror)
			)
		)
		(property "Value" ""
			(at 0 0 90)
			(layer "B.Fab")
			(effects
				(font
					(size 1.27 1.27)
				)
				(justify mirror)
			)
		)
		(duplicate_pad_numbers_are_jumpers no)
		(fp_line
			(start 0.7874 -0.4064)
			(end -0.7874 -0.4064)
			(stroke
				(width 0.1524)
				(type default)
			)
			(layer "B.SilkS")
		)
		(fp_line
			(start -0.7874 -0.4064)
			(end -0.7874 0.4064)
			(stroke
				(width 0.1524)
				(type default)
			)
			(layer "B.SilkS")
		)
		(fp_line
			(start 0.7874 0.4064)
			(end 0.7874 -0.4064)
			(stroke
				(width 0.1524)
				(type default)
			)
			(layer "B.SilkS")
		)
		(fp_line
			(start -0.7874 0.4064)
			(end 0.7874 0.4064)
			(stroke
				(width 0.1524)
				(type default)
			)
			(layer "B.SilkS")
		)
		(fp_line
			(start 0.67945 -0.305054)
			(end 0.12065 -0.305054)
			(stroke
				(width 0.1)
				(type default)
			)
			(layer "B.Fab")
		)
		(fp_line
			(start 0.12065 -0.305054)
			(end 0.12065 -0.2794)
			(stroke
				(width 0.1)
				(type default)
			)
			(layer "B.Fab")
		)
		(fp_line
			(start -0.12065 -0.3048)
			(end -0.67945 -0.3048)
			(stroke
				(width 0.1)
				(type default)
			)
			(layer "B.Fab")
		)
		(fp_line
			(start -0.67945 -0.3048)
			(end -0.67945 0.3048)
			(stroke
				(width 0.1)
				(type default)
			)
			(layer "B.Fab")
		)
		(fp_line
			(start 0.12065 -0.2794)
			(end -0.12065 -0.2794)
			(stroke
				(width 0.1)
				(type default)
			)
			(layer "B.Fab")
		)
		(fp_line
			(start -0.12065 -0.2794)
			(end -0.12065 -0.3048)
			(stroke
				(width 0.1)
				(type default)
			)
			(layer "B.Fab")
		)
		(fp_line
			(start 0.12065 0.2794)
			(end 0.12065 0.3048)
			(stroke
				(width 0.1)
				(type default)
			)
			(layer "B.Fab")
		)
		(fp_line
			(start -0.120396 0.2794)
			(end 0.12065 0.2794)
			(stroke
				(width 0.1)
				(type default)
			)
			(layer "B.Fab")
		)
		(fp_line
			(start 0.67945 0.3048)
			(end 0.67945 -0.305054)
			(stroke
				(width 0.1)
				(type default)
			)
			(layer "B.Fab")
		)
		(fp_line
			(start 0.12065 0.3048)
			(end 0.67945 0.3048)
			(stroke
				(width 0.1)
				(type default)
			)
			(layer "B.Fab")
		)
		(fp_line
			(start -0.120396 0.3048)
			(end -0.120396 0.2794)
			(stroke
				(width 0.1)
				(type default)
			)
			(layer "B.Fab")
		)
		(fp_line
			(start -0.67945 0.3048)
			(end -0.120396 0.3048)
			(stroke
				(width 0.1)
				(type default)
			)
			(layer "B.Fab")
		)
		(pad "1" smd circle
			(at 0.40005 0 270)
			(size 0 0)
			(layers "B.Cu" "B.Mask" "B.Paste")
			(net "DBP_CPU0_HOOK9_MBP3_GTL_QS_R_N")
		)
		(pad "2" smd circle
			(at -0.40005 0 270)
			(size 0 0)
			(layers "B.Cu" "B.Mask" "B.Paste")
			(net "DBP_CPU_HOOK9_MBP3_GTL_QS_N")
		)
	)
	(footprint ""
		(layer "B.Cu")
		(at 60.873132 -258.466844 -90)
		(property "Reference" "C458"
			(at 0 0 90)
			(layer "B.SilkS")
			(hide yes)
			(effects
				(font
					(size 1.27 1.27)
				)
				(justify mirror)
			)
		)
		(property "Value" ""
			(at 0 0 90)
			(layer "B.Fab")
			(effects
				(font
					(size 1.27 1.27)
				)
				(justify mirror)
			)
		)
		(duplicate_pad_numbers_are_jumpers no)
		(fp_line
			(start -1.524 0.762)
			(end 1.524 0.762)
			(stroke
				(width 0.1524)
				(type default)
			)
			(layer "B.SilkS")
		)
		(fp_line
			(start 1.524 0.762)
			(end 1.524 -0.762)
			(stroke
				(width 0.1524)
				(type default)
			)
			(layer "B.SilkS")
		)
		(fp_line
			(start -1.524 -0.762)
			(end -1.524 0.762)
			(stroke
				(width 0.1524)
				(type default)
			)
			(layer "B.SilkS")
		)
		(fp_line
			(start 1.524 -0.762)
			(end -1.524 -0.762)
			(stroke
				(width 0.1524)
				(type default)
			)
			(layer "B.SilkS")
		)
		(fp_line
			(start -1.1049 0.724916)
			(end -1.1049 -0.724916)
			(stroke
				(width 0.1)
				(type default)
			)
			(layer "B.Fab")
		)
		(fp_line
			(start 1.1049 0.724916)
			(end -1.1049 0.724916)
			(stroke
				(width 0.1)
				(type default)
			)
			(layer "B.Fab")
		)
		(fp_line
			(start -1.1049 -0.724916)
			(end 1.1049 -0.724916)
			(stroke
				(width 0.1)
				(type default)
			)
			(layer "B.Fab")
		)
		(fp_line
			(start 1.1049 -0.724916)
			(end 1.1049 0.724916)
			(stroke
				(width 0.1)
				(type default)
			)
			(layer "B.Fab")
		)
		(pad "1" smd rect
			(at 0.889 0 270)
			(size 1.016 1.27)
			(layers "B.Cu" "B.Mask" "B.Paste")
			(net "PVCCFA_EHV_FIVRA_CPU1")
		)
		(pad "2" smd rect
			(at -0.889 0 270)
			(size 1.016 1.27)
			(layers "B.Cu" "B.Mask" "B.Paste")
			(net "GND")
		)
	)
	(footprint ""
		(layer "B.Cu")
		(at 128.85674 -20.996148 90)
		(property "Reference" "R4280"
			(at 0 0 90)
			(layer "B.SilkS")
			(hide yes)
			(effects
				(font
					(size 1.27 1.27)
				)
				(justify mirror)
			)
		)
		(property "Value" ""
			(at 0 0 90)
			(layer "B.Fab")
			(effects
				(font
					(size 1.27 1.27)
				)
				(justify mirror)
			)
		)
		(duplicate_pad_numbers_are_jumpers no)
		(fp_line
			(start 0.7874 -0.4064)
			(end -0.7874 -0.4064)
			(stroke
				(width 0.1524)
				(type default)
			)
			(layer "B.SilkS")
		)
		(fp_line
			(start -0.7874 -0.4064)
			(end -0.7874 0.4064)
			(stroke
				(width 0.1524)
				(type default)
			)
			(layer "B.SilkS")
		)
		(fp_line
			(start 0.7874 0.4064)
			(end 0.7874 -0.4064)
			(stroke
				(width 0.1524)
				(type default)
			)
			(layer "B.SilkS")
		)
		(fp_line
			(start -0.7874 0.4064)
			(end 0.7874 0.4064)
			(stroke
				(width 0.1524)
				(type default)
			)
			(layer "B.SilkS")
		)
		(fp_line
			(start 0.67945 -0.305054)
			(end 0.12065 -0.305054)
			(stroke
				(width 0.1)
				(type default)
			)
			(layer "B.Fab")
		)
		(fp_line
			(start 0.12065 -0.305054)
			(end 0.12065 -0.2794)
			(stroke
				(width 0.1)
				(type default)
			)
			(layer "B.Fab")
		)
		(fp_line
			(start -0.12065 -0.3048)
			(end -0.67945 -0.3048)
			(stroke
				(width 0.1)
				(type default)
			)
			(layer "B.Fab")
		)
		(fp_line
			(start -0.67945 -0.3048)
			(end -0.67945 0.3048)
			(stroke
				(width 0.1)
				(type default)
			)
			(layer "B.Fab")
		)
		(fp_line
			(start 0.12065 -0.2794)
			(end -0.12065 -0.2794)
			(stroke
				(width 0.1)
				(type default)
			)
			(layer "B.Fab")
		)
		(fp_line
			(start -0.12065 -0.2794)
			(end -0.12065 -0.3048)
			(stroke
				(width 0.1)
				(type default)
			)
			(layer "B.Fab")
		)
		(fp_line
			(start 0.12065 0.2794)
			(end 0.12065 0.3048)
			(stroke
				(width 0.1)
				(type default)
			)
			(layer "B.Fab")
		)
		(fp_line
			(start -0.120396 0.2794)
			(end 0.12065 0.2794)
			(stroke
				(width 0.1)
				(type default)
			)
			(layer "B.Fab")
		)
		(fp_line
			(start 0.67945 0.3048)
			(end 0.67945 -0.305054)
			(stroke
				(width 0.1)
				(type default)
			)
			(layer "B.Fab")
		)
		(fp_line
			(start 0.12065 0.3048)
			(end 0.67945 0.3048)
			(stroke
				(width 0.1)
				(type default)
			)
			(layer "B.Fab")
		)
		(fp_line
			(start -0.120396 0.3048)
			(end -0.120396 0.2794)
			(stroke
				(width 0.1)
				(type default)
			)
			(layer "B.Fab")
		)
		(fp_line
			(start -0.67945 0.3048)
			(end -0.120396 0.3048)
			(stroke
				(width 0.1)
				(type default)
			)
			(layer "B.Fab")
		)
		(pad "1" smd circle
			(at 0.40005 0 270)
			(size 0 0)
			(layers "B.Cu" "B.Mask" "B.Paste")
			(net "FM_USB3_1_FGA")
		)
		(pad "2" smd circle
			(at -0.40005 0 270)
			(size 0 0)
			(layers "B.Cu" "B.Mask" "B.Paste")
			(net "GND")
		)
	)
	(footprint ""
		(layer "B.Cu")
		(at 62.996572 -161.71926)
		(property "Reference" "PC2"
			(at 0 0 0)
			(layer "B.SilkS")
			(hide yes)
			(effects
				(font
					(size 1.27 1.27)
				)
				(justify mirror)
			)
		)
		(property "Value" ""
			(at 0 0 0)
			(layer "B.Fab")
			(effects
				(font
					(size 1.27 1.27)
				)
				(justify mirror)
			)
		)
		(duplicate_pad_numbers_are_jumpers no)
		(fp_line
			(start -1.524 -0.762)
			(end -1.524 0.762)
			(stroke
				(width 0.1524)
				(type default)
			)
			(layer "B.SilkS")
		)
		(fp_line
			(start -1.524 0.762)
			(end 1.524 0.762)
			(stroke
				(width 0.1524)
				(type default)
			)
			(layer "B.SilkS")
		)
		(fp_line
			(start 1.524 -0.762)
			(end -1.524 -0.762)
			(stroke
				(width 0.1524)
				(type default)
			)
			(layer "B.SilkS")
		)
		(fp_line
			(start 1.524 0.762)
			(end 1.524 -0.762)
			(stroke
				(width 0.1524)
				(type default)
			)
			(layer "B.SilkS")
		)
		(fp_line
			(start -1.1049 -0.724916)
			(end 1.1049 -0.724916)
			(stroke
				(width 0.1)
				(type default)
			)
			(layer "B.Fab")
		)
		(fp_line
			(start -1.1049 0.724916)
			(end -1.1049 -0.724916)
			(stroke
				(width 0.1)
				(type default)
			)
			(layer "B.Fab")
		)
		(fp_line
			(start 1.1049 -0.724916)
			(end 1.1049 0.724916)
			(stroke
				(width 0.1)
				(type default)
			)
			(layer "B.Fab")
		)
		(fp_line
			(start 1.1049 0.724916)
			(end -1.1049 0.724916)
			(stroke
				(width 0.1)
				(type default)
			)
			(layer "B.Fab")
		)
		(pad "1" smd rect
			(at 0.889 0)
			(size 1.016 1.27)
			(layers "B.Cu" "B.Mask" "B.Paste")
			(net "PVCCD_HV_CPU1")
		)
		(pad "2" smd rect
			(at -0.889 0)
			(size 1.016 1.27)
			(layers "B.Cu" "B.Mask" "B.Paste")
			(net "GND")
		)
	)
	(footprint ""
		(layer "B.Cu")
		(at 332.657196 -61.821314 45)
		(property "Reference" "C1272"
			(at 0 0 45)
			(layer "B.SilkS")
			(hide yes)
			(effects
				(font
					(size 1.27 1.27)
				)
				(justify mirror)
			)
		)
		(property "Value" ""
			(at 0 0 45)
			(layer "B.Fab")
			(effects
				(font
					(size 1.27 1.27)
				)
				(justify mirror)
			)
		)
		(duplicate_pad_numbers_are_jumpers no)
		(fp_line
			(start -1.523949 -0.762065)
			(end -1.523949 0.762065)
			(stroke
				(width 0.1524)
				(type default)
			)
			(layer "B.SilkS")
		)
		(fp_line
			(start -1.523949 0.762065)
			(end 1.523949 0.762065)
			(stroke
				(width 0.1524)
				(type default)
			)
			(layer "B.SilkS")
		)
		(fp_line
			(start 1.523949 -0.762065)
			(end -1.523949 -0.762065)
			(stroke
				(width 0.1524)
				(type default)
			)
			(layer "B.SilkS")
		)
		(fp_line
			(start 1.523949 0.762065)
			(end 1.523949 -0.762065)
			(stroke
				(width 0.1524)
				(type default)
			)
			(layer "B.SilkS")
		)
		(fp_line
			(start -1.104931 -0.724886)
			(end 1.104931 -0.724886)
			(stroke
				(width 0.1)
				(type default)
			)
			(layer "B.Fab")
		)
		(fp_line
			(start -1.104931 0.724886)
			(end -1.104931 -0.724886)
			(stroke
				(width 0.1)
				(type default)
			)
			(layer "B.Fab")
		)
		(fp_line
			(start 1.104931 -0.724886)
			(end 1.104931 0.724886)
			(stroke
				(width 0.1)
				(type default)
			)
			(layer "B.Fab")
		)
		(fp_line
			(start 1.104931 0.724886)
			(end -1.104931 0.724886)
			(stroke
				(width 0.1)
				(type default)
			)
			(layer "B.Fab")
		)
		(pad "1" smd rect
			(at 0.889 0 45)
			(size 1.016 1.27)
			(layers "B.Cu" "B.Mask" "B.Paste")
			(net "P1V05_PCH_PLL_AUX")
		)
		(pad "2" smd rect
			(at -0.889 0 45)
			(size 1.016 1.27)
			(layers "B.Cu" "B.Mask" "B.Paste")
			(net "GND")
		)
	)
	(footprint ""
		(layer "B.Cu")
		(at 180.155596 -114.575336 180)
		(property "Reference" "C1154"
			(at 0 0 0)
			(layer "B.SilkS")
			(hide yes)
			(effects
				(font
					(size 1.27 1.27)
				)
				(justify mirror)
			)
		)
		(property "Value" ""
			(at 0 0 0)
			(layer "B.Fab")
			(effects
				(font
					(size 1.27 1.27)
				)
				(justify mirror)
			)
		)
		(duplicate_pad_numbers_are_jumpers no)
		(fp_line
			(start 0.69215 0.2921)
			(end 0.69215 -0.2921)
			(stroke
				(width 0.1524)
				(type default)
			)
			(layer "B.SilkS")
		)
		(fp_line
			(start 0.69215 -0.2921)
			(end -0.69215 -0.2921)
			(stroke
				(width 0.1524)
				(type default)
			)
			(layer "B.SilkS")
		)
		(fp_line
			(start -0.69215 0.2921)
			(end 0.69215 0.2921)
			(stroke
				(width 0.1524)
				(type default)
			)
			(layer "B.SilkS")
		)
		(fp_line
			(start -0.69215 -0.2921)
			(end -0.69215 0.2921)
			(stroke
				(width 0.1524)
				(type default)
			)
			(layer "B.SilkS")
		)
		(fp_line
			(start 0.51435 0.2794)
			(end 0.51435 -0.2794)
			(stroke
				(width 0.1)
				(type default)
			)
			(layer "B.Fab")
		)
		(fp_line
			(start 0.51435 -0.2794)
			(end -0.51435 -0.2794)
			(stroke
				(width 0.1)
				(type default)
			)
			(layer "B.Fab")
		)
		(fp_line
			(start -0.51435 0.2794)
			(end 0.51435 0.2794)
			(stroke
				(width 0.1)
				(type default)
			)
			(layer "B.Fab")
		)
		(fp_line
			(start -0.51435 -0.2794)
			(end -0.51435 0.2794)
			(stroke
				(width 0.1)
				(type default)
			)
			(layer "B.Fab")
		)
		(pad "1" smd circle
			(at 0.40005 0)
			(size 0 0)
			(layers "B.Cu" "B.Mask" "B.Paste")
			(net "VCC_PLD_CORE")
		)
		(pad "2" smd circle
			(at -0.40005 0)
			(size 0 0)
			(layers "B.Cu" "B.Mask" "B.Paste")
			(net "GND")
		)
		(zone
			(layer "B.Cu")
			(hatch none 0.5)
			(connect_pads
				(clearance 0)
			)
			(min_thickness 0.25)
			(keepout
				(tracks not_allowed)
				(vias allowed)
				(pads allowed)
				(copperpour not_allowed)
				(footprints allowed)
			)
			(placement
				(enabled no)
				(sheetname "")
			)
			(fill
				(thermal_gap 0.5)
				(thermal_bridge_width 0.5)
				(island_removal_mode 0)
			)
			(polygon
				(pts
					(xy 179.965096 -114.662966) (xy 180.056536 -114.721132) (xy 180.255926 -114.721132) (xy 180.346096 -114.662966)
					(xy 180.346096 -114.487706) (xy 180.255926 -114.429286) (xy 180.056536 -114.429286) (xy 179.965096 -114.487452)
				)
			)
		)
	)
)
